# T6G (Grand Teton) — schematic netlist excerpt (pin names and nets, part order shuffled) for the footprints in the layout excerpt that follows; sources: Cadence DE-HDL packaged netlist, KiCad conversion of 04192023_DAF0TMB3IC0_F0TG_MB_C_brd_V02_OCP.brd

R3295  Q_RES  4.7K 1% CHIP  pkg 0402LF  page 144 : A = P3V3_M2_0 ; B = LED_HDD_ACTIVITY_N
R1528  Q_RES  33 5% CHIP  pkg 0402LF  page 172 : A = PRSNT_HDT_N ; B = PRSNT_HDT_R_N

(kicad_pcb
	(version 20260206)
	(generator "pcbnew")
	(generator_version "10.0")
	(general
		(thickness 1.6)
		(legacy_teardrops no)
	)
	(paper "A4")
	(title_block
		(title "04192023_DAF0TMB3IC0_F0TG_MB_C_brd_V02_OCP.brd")
		(comment 1 "Grand Teton / footprints 1520-1521 of 8354")
	)
	(layers
		(0 "F.Cu" signal "TOP")
		(4 "In1.Cu" signal "GND")
		(6 "In2.Cu" signal "IN1")
		(8 "In3.Cu" signal "GND1")
		(10 "In4.Cu" signal "IN2")
		(12 "In5.Cu" signal "GND2")
		(14 "In6.Cu" signal "IN3")
		(16 "In7.Cu" signal "GND3")
		(18 "In8.Cu" signal "VCC")
		(20 "In9.Cu" signal "VCC1")
		(22 "In10.Cu" signal "GND4")
		(24 "In11.Cu" signal "IN4")
		(26 "In12.Cu" signal "GND5")
		(28 "In13.Cu" signal "IN5")
		(30 "In14.Cu" signal "GND6")
		(32 "In15.Cu" signal "IN6")
		(34 "In16.Cu" signal "GND7")
		(2 "B.Cu" signal "BOTTOM")
		(9 "F.Adhes" user "F.Adhesive")
		(11 "B.Adhes" user "B.Adhesive")
		(13 "F.Paste" user "Package Geometry/Pastemask Top")
		(15 "B.Paste" user "Package Geometry/Pastemask Bottom")
		(5 "F.SilkS" user "Ref Des/Silkscreen Top")
		(7 "B.SilkS" user "Ref Des/Silkscreen Bottom")
		(1 "F.Mask" user "Board Geometry/Soldermask Top")
		(3 "B.Mask" user "Board Geometry/Soldermask Bottom")
		(17 "Dwgs.User" user "User.Drawings")
		(19 "Cmts.User" user "User.Comments")
		(21 "Eco1.User" user "User.Eco1")
		(23 "Eco2.User" user "User.Eco2")
		(25 "Edge.Cuts" user "Board Geometry/Outline")
		(27 "Margin" user)
		(31 "F.CrtYd" user "Package Geometry/Place Bound Top")
		(29 "B.CrtYd" user "Package Geometry/Place Bound Bottom")
		(35 "F.Fab" user "Ref Des/Assembly Top")
		(33 "B.Fab" user "Ref Des/Assembly Bottom")
	)
	(footprint ""
		(layer "F.Cu")
		(at 403.682962 -54.4195 180)
		(property "Reference" "R1528"
			(at 0 0 180)
			(layer "F.SilkS")
			(hide yes)
			(effects
				(font
					(size 1.27 1.27)
				)
			)
		)
		(property "Value" ""
			(at 0 0 180)
			(layer "F.Fab")
			(effects
				(font
					(size 1.27 1.27)
				)
			)
		)
		(duplicate_pad_numbers_are_jumpers no)
		(fp_line
			(start 0.7874 0.4064)
			(end -0.7874 0.4064)
			(stroke
				(width 0.1524)
				(type default)
			)
			(layer "F.SilkS")
		)
		(fp_line
			(start 0.7874 -0.4064)
			(end 0.7874 0.4064)
			(stroke
				(width 0.1524)
				(type default)
			)
			(layer "F.SilkS")
		)
		(fp_line
			(start -0.7874 0.4064)
			(end -0.7874 -0.4064)
			(stroke
				(width 0.1524)
				(type default)
			)
			(layer "F.SilkS")
		)
		(fp_line
			(start -0.7874 -0.4064)
			(end 0.7874 -0.4064)
			(stroke
				(width 0.1524)
				(type default)
			)
			(layer "F.SilkS")
		)
		(fp_line
			(start 0.67945 0.3048)
			(end 0.120396 0.3048)
			(stroke
				(width 0.1)
				(type default)
			)
			(layer "F.Fab")
		)
		(fp_line
			(start 0.67945 -0.3048)
			(end 0.67945 0.3048)
			(stroke
				(width 0.1)
				(type default)
			)
			(layer "F.Fab")
		)
		(fp_line
			(start 0.12065 -0.2794)
			(end 0.12065 -0.3048)
			(stroke
				(width 0.1)
				(type default)
			)
			(layer "F.Fab")
		)
		(fp_line
			(start 0.12065 -0.3048)
			(end 0.67945 -0.3048)
			(stroke
				(width 0.1)
				(type default)
			)
			(layer "F.Fab")
		)
		(fp_line
			(start 0.120396 0.3048)
			(end 0.120396 0.2794)
			(stroke
				(width 0.1)
				(type default)
			)
			(layer "F.Fab")
		)
		(fp_line
			(start 0.120396 0.2794)
			(end -0.12065 0.2794)
			(stroke
				(width 0.1)
				(type default)
			)
			(layer "F.Fab")
		)
		(fp_line
			(start -0.12065 0.3048)
			(end -0.67945 0.3048)
			(stroke
				(width 0.1)
				(type default)
			)
			(layer "F.Fab")
		)
		(fp_line
			(start -0.12065 0.2794)
			(end -0.12065 0.3048)
			(stroke
				(width 0.1)
				(type default)
			)
			(layer "F.Fab")
		)
		(fp_line
			(start -0.12065 -0.2794)
			(end 0.12065 -0.2794)
			(stroke
				(width 0.1)
				(type default)
			)
			(layer "F.Fab")
		)
		(fp_line
			(start -0.12065 -0.305054)
			(end -0.12065 -0.2794)
			(stroke
				(width 0.1)
				(type default)
			)
			(layer "F.Fab")
		)
		(fp_line
			(start -0.67945 0.3048)
			(end -0.67945 -0.305054)
			(stroke
				(width 0.1)
				(type default)
			)
			(layer "F.Fab")
		)
		(fp_line
			(start -0.67945 -0.305054)
			(end -0.12065 -0.305054)
			(stroke
				(width 0.1)
				(type default)
			)
			(layer "F.Fab")
		)
		(pad "1" smd circle
			(at -0.40005 0 180)
			(size 0 0)
			(layers "F.Cu" "F.Mask" "F.Paste")
			(net "PRSNT_HDT_N")
		)
		(pad "2" smd circle
			(at 0.40005 0 180)
			(size 0 0)
			(layers "F.Cu" "F.Mask" "F.Paste")
			(net "PRSNT_HDT_R_N")
		)
	)
	(footprint ""
		(layer "F.Cu")
		(at 150.31974 -102.688898)
		(property "Reference" "R3295"
			(at 0 0 0)
			(layer "F.SilkS")
			(hide yes)
			(effects
				(font
					(size 1.27 1.27)
				)
			)
		)
		(property "Value" ""
			(at 0 0 0)
			(layer "F.Fab")
			(effects
				(font
					(size 1.27 1.27)
				)
			)
		)
		(duplicate_pad_numbers_are_jumpers no)
		(fp_line
			(start -0.7874 -0.4064)
			(end 0.7874 -0.4064)
			(stroke
				(width 0.1524)
				(type default)
			)
			(layer "F.SilkS")
		)
		(fp_line
			(start -0.7874 0.4064)
			(end -0.7874 -0.4064)
			(stroke
				(width 0.1524)
				(type default)
			)
			(layer "F.SilkS")
		)
		(fp_line
			(start 0.7874 -0.4064)
			(end 0.7874 0.4064)
			(stroke
				(width 0.1524)
				(type default)
			)
			(layer "F.SilkS")
		)
		(fp_line
			(start 0.7874 0.4064)
			(end -0.7874 0.4064)
			(stroke
				(width 0.1524)
				(type default)
			)
			(layer "F.SilkS")
		)
		(fp_line
			(start -0.67945 -0.305054)
			(end -0.12065 -0.305054)
			(stroke
				(width 0.1)
				(type default)
			)
			(layer "F.Fab")
		)
		(fp_line
			(start -0.67945 0.3048)
			(end -0.67945 -0.305054)
			(stroke
				(width 0.1)
				(type default)
			)
			(layer "F.Fab")
		)
		(fp_line
			(start -0.12065 -0.305054)
			(end -0.12065 -0.2794)
			(stroke
				(width 0.1)
				(type default)
			)
			(layer "F.Fab")
		)
		(fp_line
			(start -0.12065 -0.2794)
			(end 0.12065 -0.2794)
			(stroke
				(width 0.1)
				(type default)
			)
			(layer "F.Fab")
		)
		(fp_line
			(start -0.12065 0.2794)
			(end -0.12065 0.3048)
			(stroke
				(width 0.1)
				(type default)
			)
			(layer "F.Fab")
		)
		(fp_line
			(start -0.12065 0.3048)
			(end -0.67945 0.3048)
			(stroke
				(width 0.1)
				(type default)
			)
			(layer "F.Fab")
		)
		(fp_line
			(start 0.120396 0.2794)
			(end -0.12065 0.2794)
			(stroke
				(width 0.1)
				(type default)
			)
			(layer "F.Fab")
		)
		(fp_line
			(start 0.120396 0.3048)
			(end 0.120396 0.2794)
			(stroke
				(width 0.1)
				(type default)
			)
			(layer "F.Fab")
		)
		(fp_line
			(start 0.12065 -0.3048)
			(end 0.67945 -0.3048)
			(stroke
				(width 0.1)
				(type default)
			)
			(layer "F.Fab")
		)
		(fp_line
			(start 0.12065 -0.2794)
			(end 0.12065 -0.3048)
			(stroke
				(width 0.1)
				(type default)
			)
			(layer "F.Fab")
		)
		(fp_line
			(start 0.67945 -0.3048)
			(end 0.67945 0.3048)
			(stroke
				(width 0.1)
				(type default)
			)
			(layer "F.Fab")
		)
		(fp_line
			(start 0.67945 0.3048)
			(end 0.120396 0.3048)
			(stroke
				(width 0.1)
				(type default)
			)
			(layer "F.Fab")
		)
		(pad "1" smd circle
			(at -0.40005 0)
			(size 0 0)
			(layers "F.Cu" "F.Mask" "F.Paste")
			(net "P3V3_M2_0")
		)
		(pad "2" smd circle
			(at 0.40005 0)
			(size 0 0)
			(layers "F.Cu" "F.Mask" "F.Paste")
			(net "LED_HDD_ACTIVITY_N")
		)
	)
)
